(kicad_pcb
	(version 20260206)
	(generator "pcbnew")
	(generator_version "10.0")
	(general
		(thickness 1.6)
		(legacy_teardrops no)
	)
	(paper "A4")
	(title_block
		(title "01162023_DA0F0TEBIF0_F0T_Expander_BD_F_brd_V02_OCP.brd")
		(comment 1 "Grand Teton / footprints 4771-4778 of 9728")
	)
	(layers
		(0 "F.Cu" signal "TOP")
		(4 "In1.Cu" signal "GND")
		(6 "In2.Cu" signal "VCC")
		(8 "In3.Cu" signal "VCC1")
		(10 "In4.Cu" signal "GND1")
		(12 "In5.Cu" signal "IN1")
		(14 "In6.Cu" signal "GND2")
		(16 "In7.Cu" signal "IN2")
		(18 "In8.Cu" signal "GND3")
		(20 "In9.Cu" signal "IN3")
		(22 "In10.Cu" signal "GND4")
		(24 "In11.Cu" signal "IN4")
		(26 "In12.Cu" signal "GND5")
		(28 "In13.Cu" signal "IN5")
		(30 "In14.Cu" signal "GND6")
		(32 "In15.Cu" signal "IN6")
		(34 "In16.Cu" signal "GND7")
		(2 "B.Cu" signal "BOTTOM")
		(9 "F.Adhes" user "F.Adhesive")
		(11 "B.Adhes" user "B.Adhesive")
		(13 "F.Paste" user "Package Geometry/Pastemask Top")
		(15 "B.Paste" user "Package Geometry/Pastemask Bottom")
		(5 "F.SilkS" user "Ref Des/Silkscreen Top")
		(7 "B.SilkS" user "Ref Des/Silkscreen Bottom")
		(1 "F.Mask" user "Board Geometry/Soldermask Top")
		(3 "B.Mask" user "Board Geometry/Soldermask Bottom")
		(17 "Dwgs.User" user "User.Drawings")
		(19 "Cmts.User" user "User.Comments")
		(21 "Eco1.User" user "User.Eco1")
		(23 "Eco2.User" user "User.Eco2")
		(25 "Edge.Cuts" user "Board Geometry/Outline")
		(27 "Margin" user)
		(31 "F.CrtYd" user "Package Geometry/Place Bound Top")
		(29 "B.CrtYd" user "Package Geometry/Place Bound Bottom")
		(35 "F.Fab" user "Ref Des/Assembly Top")
		(33 "B.Fab" user "Ref Des/Assembly Bottom")
	)
	(footprint ""
		(layer "F.Cu")
		(at 210.130136 -181.613556 -90)
		(property "Reference" "R5300"
			(at 0 0 270)
			(layer "F.SilkS")
			(hide yes)
			(effects
				(font
					(size 1.27 1.27)
				)
			)
		)
		(property "Value" ""
			(at 0 0 270)
			(layer "F.Fab")
			(effects
				(font
					(size 1.27 1.27)
				)
			)
		)
		(duplicate_pad_numbers_are_jumpers no)
		(fp_line
			(start -0.7874 0.4064)
			(end -0.7874 -0.4064)
			(stroke
				(width 0.1524)
				(type default)
			)
			(layer "F.SilkS")
		)
		(fp_line
			(start 0.7874 0.4064)
			(end -0.7874 0.4064)
			(stroke
				(width 0.1524)
				(type default)
			)
			(layer "F.SilkS")
		)
		(fp_line
			(start -0.7874 -0.4064)
			(end 0.7874 -0.4064)
			(stroke
				(width 0.1524)
				(type default)
			)
			(layer "F.SilkS")
		)
		(fp_line
			(start 0.7874 -0.4064)
			(end 0.7874 0.4064)
			(stroke
				(width 0.1524)
				(type default)
			)
			(layer "F.SilkS")
		)
		(fp_line
			(start -0.67945 0.3048)
			(end -0.67945 -0.305054)
			(stroke
				(width 0.1)
				(type default)
			)
			(layer "F.Fab")
		)
		(fp_line
			(start -0.12065 0.3048)
			(end -0.67945 0.3048)
			(stroke
				(width 0.1)
				(type default)
			)
			(layer "F.Fab")
		)
		(fp_line
			(start 0.120396 0.3048)
			(end 0.120396 0.2794)
			(stroke
				(width 0.1)
				(type default)
			)
			(layer "F.Fab")
		)
		(fp_line
			(start 0.67945 0.3048)
			(end 0.120396 0.3048)
			(stroke
				(width 0.1)
				(type default)
			)
			(layer "F.Fab")
		)
		(fp_line
			(start -0.12065 0.2794)
			(end -0.12065 0.3048)
			(stroke
				(width 0.1)
				(type default)
			)
			(layer "F.Fab")
		)
		(fp_line
			(start 0.120396 0.2794)
			(end -0.12065 0.2794)
			(stroke
				(width 0.1)
				(type default)
			)
			(layer "F.Fab")
		)
		(fp_line
			(start -0.12065 -0.2794)
			(end 0.12065 -0.2794)
			(stroke
				(width 0.1)
				(type default)
			)
			(layer "F.Fab")
		)
		(fp_line
			(start 0.12065 -0.2794)
			(end 0.12065 -0.3048)
			(stroke
				(width 0.1)
				(type default)
			)
			(layer "F.Fab")
		)
		(fp_line
			(start 0.12065 -0.3048)
			(end 0.67945 -0.3048)
			(stroke
				(width 0.1)
				(type default)
			)
			(layer "F.Fab")
		)
		(fp_line
			(start 0.67945 -0.3048)
			(end 0.67945 0.3048)
			(stroke
				(width 0.1)
				(type default)
			)
			(layer "F.Fab")
		)
		(fp_line
			(start -0.67945 -0.305054)
			(end -0.12065 -0.305054)
			(stroke
				(width 0.1)
				(type default)
			)
			(layer "F.Fab")
		)
		(fp_line
			(start -0.12065 -0.305054)
			(end -0.12065 -0.2794)
			(stroke
				(width 0.1)
				(type default)
			)
			(layer "F.Fab")
		)
		(pad "1" smd circle
			(at -0.40005 0 270)
			(size 0 0)
			(layers "F.Cu" "F.Mask" "F.Paste")
			(net "SEL_FLASH_PEX3_BUF")
		)
		(pad "2" smd circle
			(at 0.40005 0 270)
			(size 0 0)
			(layers "F.Cu" "F.Mask" "F.Paste")
			(net "SEL_FLASH_PEX3_BUF_R")
		)
	)
	(footprint ""
		(layer "F.Cu")
		(at 374.567958 -56.353456)
		(property "Reference" "C2870"
			(at 0 0 0)
			(layer "F.SilkS")
			(hide yes)
			(effects
				(font
					(size 1.27 1.27)
				)
			)
		)
		(property "Value" ""
			(at 0 0 0)
			(layer "F.Fab")
			(effects
				(font
					(size 1.27 1.27)
				)
			)
		)
		(duplicate_pad_numbers_are_jumpers no)
		(fp_line
			(start -0.7874 -0.4064)
			(end 0.7874 -0.4064)
			(stroke
				(width 0.1524)
				(type default)
			)
			(layer "F.SilkS")
		)
		(fp_line
			(start -0.7874 0.4064)
			(end -0.7874 -0.4064)
			(stroke
				(width 0.1524)
				(type default)
			)
			(layer "F.SilkS")
		)
		(fp_line
			(start 0.7874 -0.4064)
			(end 0.7874 0.4064)
			(stroke
				(width 0.1524)
				(type default)
			)
			(layer "F.SilkS")
		)
		(fp_line
			(start 0.7874 0.4064)
			(end -0.7874 0.4064)
			(stroke
				(width 0.1524)
				(type default)
			)
			(layer "F.SilkS")
		)
		(fp_line
			(start -0.67945 -0.305054)
			(end -0.12065 -0.305054)
			(stroke
				(width 0.1)
				(type default)
			)
			(layer "F.Fab")
		)
		(fp_line
			(start -0.67945 0.3048)
			(end -0.67945 -0.305054)
			(stroke
				(width 0.1)
				(type default)
			)
			(layer "F.Fab")
		)
		(fp_line
			(start -0.12065 -0.305054)
			(end -0.12065 -0.2794)
			(stroke
				(width 0.1)
				(type default)
			)
			(layer "F.Fab")
		)
		(fp_line
			(start -0.12065 -0.2794)
			(end 0.12065 -0.2794)
			(stroke
				(width 0.1)
				(type default)
			)
			(layer "F.Fab")
		)
		(fp_line
			(start -0.12065 0.2794)
			(end -0.12065 0.3048)
			(stroke
				(width 0.1)
				(type default)
			)
			(layer "F.Fab")
		)
		(fp_line
			(start -0.12065 0.3048)
			(end -0.67945 0.3048)
			(stroke
				(width 0.1)
				(type default)
			)
			(layer "F.Fab")
		)
		(fp_line
			(start 0.120396 0.2794)
			(end -0.12065 0.2794)
			(stroke
				(width 0.1)
				(type default)
			)
			(layer "F.Fab")
		)
		(fp_line
			(start 0.120396 0.3048)
			(end 0.120396 0.2794)
			(stroke
				(width 0.1)
				(type default)
			)
			(layer "F.Fab")
		)
		(fp_line
			(start 0.12065 -0.3048)
			(end 0.67945 -0.3048)
			(stroke
				(width 0.1)
				(type default)
			)
			(layer "F.Fab")
		)
		(fp_line
			(start 0.12065 -0.2794)
			(end 0.12065 -0.3048)
			(stroke
				(width 0.1)
				(type default)
			)
			(layer "F.Fab")
		)
		(fp_line
			(start 0.67945 -0.3048)
			(end 0.67945 0.3048)
			(stroke
				(width 0.1)
				(type default)
			)
			(layer "F.Fab")
		)
		(fp_line
			(start 0.67945 0.3048)
			(end 0.120396 0.3048)
			(stroke
				(width 0.1)
				(type default)
			)
			(layer "F.Fab")
		)
		(pad "1" smd circle
			(at -0.40005 0)
			(size 0 0)
			(layers "F.Cu" "F.Mask" "F.Paste")
			(net "SSD12_PWR_EN_R")
		)
		(pad "2" smd circle
			(at 0.40005 0)
			(size 0 0)
			(layers "F.Cu" "F.Mask" "F.Paste")
			(net "GND")
		)
	)
	(footprint ""
		(layer "F.Cu")
		(at 70.620128 -15.649956 180)
		(property "Reference" "H116"
			(at -3.849624 -2.709418 0)
			(unlocked yes)
			(layer "B.SilkS")
			(effects
				(font
					(size 0.7874 0.5842)
					(thickness 0.1524)
				)
				(justify left mirror)
			)
		)
		(property "Value" ""
			(at 0 0 180)
			(layer "F.Fab")
			(effects
				(font
					(size 1.27 1.27)
				)
			)
		)
		(duplicate_pad_numbers_are_jumpers no)
		(pad "1" thru_hole rect
			(at 0 0 180)
			(size 4.2164 5.0038)
			(drill 2.0066
				(offset 0.099822 0)
			)
			(layers "*.Cu" "*.Mask")
			(remove_unused_layers no)
			(net "Net_8547")
			(clearance -0.8509)
			(padstack
				(mode front_inner_back)
				(layer "Inner"
					(shape circle)
					(size 4.0132 4.0132)
					(clearance -0.7493)
				)
				(layer "B.Cu"
					(shape circle)
					(size 4.0132 4.0132)
					(clearance -0.7493)
				)
			)
		)
	)
	(footprint ""
		(layer "F.Cu")
		(at 168.378632 -343.952322 90)
		(property "Reference" "C396"
			(at 0 0 90)
			(layer "F.SilkS")
			(hide yes)
			(effects
				(font
					(size 1.27 1.27)
				)
			)
		)
		(property "Value" ""
			(at 0 0 90)
			(layer "F.Fab")
			(effects
				(font
					(size 1.27 1.27)
				)
			)
		)
		(duplicate_pad_numbers_are_jumpers no)
		(fp_line
			(start 0.299974 -0.150114)
			(end 0.299974 0.150114)
			(stroke
				(width 0.1)
				(type default)
			)
			(layer "F.Fab")
		)
		(fp_line
			(start -0.299974 -0.150114)
			(end 0.299974 -0.150114)
			(stroke
				(width 0.1)
				(type default)
			)
			(layer "F.Fab")
		)
		(fp_line
			(start 0.299974 0.150114)
			(end -0.299974 0.150114)
			(stroke
				(width 0.1)
				(type default)
			)
			(layer "F.Fab")
		)
		(fp_line
			(start -0.299974 0.150114)
			(end -0.299974 -0.150114)
			(stroke
				(width 0.1)
				(type default)
			)
			(layer "F.Fab")
		)
		(pad "1" smd rect
			(at -0.2667 0 90)
			(size 0.3048 0.381)
			(layers "F.Cu" "F.Mask" "F.Paste")
			(net "P5E_PEX1_STN7_TX_DP<115>")
		)
		(pad "2" smd rect
			(at 0.2667 0 90)
			(size 0.3048 0.381)
			(layers "F.Cu" "F.Mask" "F.Paste")
			(net "P5E_PEX1_STN7_TX_C_DP<115>")
		)
	)
	(footprint ""
		(layer "F.Cu")
		(at 237.494064 -35.264852)
		(property "Reference" "R5687"
			(at 0 0 0)
			(layer "F.SilkS")
			(hide yes)
			(effects
				(font
					(size 1.27 1.27)
				)
			)
		)
		(property "Value" ""
			(at 0 0 0)
			(layer "F.Fab")
			(effects
				(font
					(size 1.27 1.27)
				)
			)
		)
		(duplicate_pad_numbers_are_jumpers no)
		(fp_line
			(start -0.7874 -0.4064)
			(end 0.7874 -0.4064)
			(stroke
				(width 0.1524)
				(type default)
			)
			(layer "F.SilkS")
		)
		(fp_line
			(start -0.7874 0.4064)
			(end -0.7874 -0.4064)
			(stroke
				(width 0.1524)
				(type default)
			)
			(layer "F.SilkS")
		)
		(fp_line
			(start 0.7874 -0.4064)
			(end 0.7874 0.4064)
			(stroke
				(width 0.1524)
				(type default)
			)
			(layer "F.SilkS")
		)
		(fp_line
			(start 0.7874 0.4064)
			(end -0.7874 0.4064)
			(stroke
				(width 0.1524)
				(type default)
			)
			(layer "F.SilkS")
		)
		(fp_line
			(start -0.67945 -0.305054)
			(end -0.12065 -0.305054)
			(stroke
				(width 0.1)
				(type default)
			)
			(layer "F.Fab")
		)
		(fp_line
			(start -0.67945 0.3048)
			(end -0.67945 -0.305054)
			(stroke
				(width 0.1)
				(type default)
			)
			(layer "F.Fab")
		)
		(fp_line
			(start -0.12065 -0.305054)
			(end -0.12065 -0.2794)
			(stroke
				(width 0.1)
				(type default)
			)
			(layer "F.Fab")
		)
		(fp_line
			(start -0.12065 -0.2794)
			(end 0.12065 -0.2794)
			(stroke
				(width 0.1)
				(type default)
			)
			(layer "F.Fab")
		)
		(fp_line
			(start -0.12065 0.2794)
			(end -0.12065 0.3048)
			(stroke
				(width 0.1)
				(type default)
			)
			(layer "F.Fab")
		)
		(fp_line
			(start -0.12065 0.3048)
			(end -0.67945 0.3048)
			(stroke
				(width 0.1)
				(type default)
			)
			(layer "F.Fab")
		)
		(fp_line
			(start 0.120396 0.2794)
			(end -0.12065 0.2794)
			(stroke
				(width 0.1)
				(type default)
			)
			(layer "F.Fab")
		)
		(fp_line
			(start 0.120396 0.3048)
			(end 0.120396 0.2794)
			(stroke
				(width 0.1)
				(type default)
			)
			(layer "F.Fab")
		)
		(fp_line
			(start 0.12065 -0.3048)
			(end 0.67945 -0.3048)
			(stroke
				(width 0.1)
				(type default)
			)
			(layer "F.Fab")
		)
		(fp_line
			(start 0.12065 -0.2794)
			(end 0.12065 -0.3048)
			(stroke
				(width 0.1)
				(type default)
			)
			(layer "F.Fab")
		)
		(fp_line
			(start 0.67945 -0.3048)
			(end 0.67945 0.3048)
			(stroke
				(width 0.1)
				(type default)
			)
			(layer "F.Fab")
		)
		(fp_line
			(start 0.67945 0.3048)
			(end 0.120396 0.3048)
			(stroke
				(width 0.1)
				(type default)
			)
			(layer "F.Fab")
		)
		(pad "1" smd circle
			(at -0.40005 0)
			(size 0 0)
			(layers "F.Cu" "F.Mask" "F.Paste")
			(net "RST_SMB_SSD8_ISO_N")
		)
		(pad "2" smd circle
			(at 0.40005 0)
			(size 0 0)
			(layers "F.Cu" "F.Mask" "F.Paste")
			(net "GND")
		)
	)
	(footprint ""
		(layer "F.Cu")
		(at 90.241882 -356.244906 90)
		(property "Reference" "C100"
			(at 0 0 90)
			(layer "F.SilkS")
			(hide yes)
			(effects
				(font
					(size 1.27 1.27)
				)
			)
		)
		(property "Value" ""
			(at 0 0 90)
			(layer "F.Fab")
			(effects
				(font
					(size 1.27 1.27)
				)
			)
		)
		(duplicate_pad_numbers_are_jumpers no)
		(fp_line
			(start 0.299974 -0.150114)
			(end 0.299974 0.150114)
			(stroke
				(width 0.1)
				(type default)
			)
			(layer "F.Fab")
		)
		(fp_line
			(start -0.299974 -0.150114)
			(end 0.299974 -0.150114)
			(stroke
				(width 0.1)
				(type default)
			)
			(layer "F.Fab")
		)
		(fp_line
			(start 0.299974 0.150114)
			(end -0.299974 0.150114)
			(stroke
				(width 0.1)
				(type default)
			)
			(layer "F.Fab")
		)
		(fp_line
			(start -0.299974 0.150114)
			(end -0.299974 -0.150114)
			(stroke
				(width 0.1)
				(type default)
			)
			(layer "F.Fab")
		)
		(pad "1" smd rect
			(at -0.2667 0 90)
			(size 0.3048 0.381)
			(layers "F.Cu" "F.Mask" "F.Paste")
			(net "P5E_PEX0_STN5_TX_DN<94>")
		)
		(pad "2" smd rect
			(at 0.2667 0 90)
			(size 0.3048 0.381)
			(layers "F.Cu" "F.Mask" "F.Paste")
			(net "P5E_PEX0_STN5_TX_C_DN<94>")
		)
	)
	(footprint ""
		(layer "F.Cu")
		(at 173.494192 -29.507688 -90)
		(property "Reference" "PC931"
			(at 0 0 270)
			(layer "F.SilkS")
			(hide yes)
			(effects
				(font
					(size 1.27 1.27)
				)
			)
		)
		(property "Value" ""
			(at 0 0 270)
			(layer "F.Fab")
			(effects
				(font
					(size 1.27 1.27)
				)
			)
		)
		(duplicate_pad_numbers_are_jumpers no)
		(fp_line
			(start -1.524 0.762)
			(end -1.524 -0.762)
			(stroke
				(width 0.1524)
				(type default)
			)
			(layer "F.SilkS")
		)
		(fp_line
			(start 1.524 0.762)
			(end -1.524 0.762)
			(stroke
				(width 0.1524)
				(type default)
			)
			(layer "F.SilkS")
		)
		(fp_line
			(start -1.524 -0.762)
			(end 1.524 -0.762)
			(stroke
				(width 0.1524)
				(type default)
			)
			(layer "F.SilkS")
		)
		(fp_line
			(start 1.524 -0.762)
			(end 1.524 0.762)
			(stroke
				(width 0.1524)
				(type default)
			)
			(layer "F.SilkS")
		)
		(fp_line
			(start -1.1049 0.724916)
			(end 1.1049 0.724916)
			(stroke
				(width 0.1)
				(type default)
			)
			(layer "F.Fab")
		)
		(fp_line
			(start 1.1049 0.724916)
			(end 1.1049 -0.724916)
			(stroke
				(width 0.1)
				(type default)
			)
			(layer "F.Fab")
		)
		(fp_line
			(start -1.1049 -0.724916)
			(end -1.1049 0.724916)
			(stroke
				(width 0.1)
				(type default)
			)
			(layer "F.Fab")
		)
		(fp_line
			(start 1.1049 -0.724916)
			(end -1.1049 -0.724916)
			(stroke
				(width 0.1)
				(type default)
			)
			(layer "F.Fab")
		)
		(pad "1" smd rect
			(at -0.889 0 90)
			(size 1.016 1.27)
			(layers "F.Cu" "F.Mask" "F.Paste")
			(net "P3V3_SSD6")
		)
		(pad "2" smd rect
			(at 0.889 0 90)
			(size 1.016 1.27)
			(layers "F.Cu" "F.Mask" "F.Paste")
			(net "GND")
		)
	)
	(footprint ""
		(layer "F.Cu")
		(at 278.758396 -414.88995 90)
		(property "Reference" "R1820"
			(at 0 0 90)
			(layer "F.SilkS")
			(hide yes)
			(effects
				(font
					(size 1.27 1.27)
				)
			)
		)
		(property "Value" ""
			(at 0 0 90)
			(layer "F.Fab")
			(effects
				(font
					(size 1.27 1.27)
				)
			)
		)
		(duplicate_pad_numbers_are_jumpers no)
		(fp_line
			(start 0.7874 -0.4064)
			(end 0.7874 0.4064)
			(stroke
				(width 0.1524)
				(type default)
			)
			(layer "F.SilkS")
		)
		(fp_line
			(start -0.7874 -0.4064)
			(end 0.7874 -0.4064)
			(stroke
				(width 0.1524)
				(type default)
			)
			(layer "F.SilkS")
		)
		(fp_line
			(start 0.7874 0.4064)
			(end -0.7874 0.4064)
			(stroke
				(width 0.1524)
				(type default)
			)
			(layer "F.SilkS")
		)
		(fp_line
			(start -0.7874 0.4064)
			(end -0.7874 -0.4064)
			(stroke
				(width 0.1524)
				(type default)
			)
			(layer "F.SilkS")
		)
		(fp_line
			(start -0.12065 -0.305054)
			(end -0.12065 -0.2794)
			(stroke
				(width 0.1)
				(type default)
			)
			(layer "F.Fab")
		)
		(fp_line
			(start -0.67945 -0.305054)
			(end -0.12065 -0.305054)
			(stroke
				(width 0.1)
				(type default)
			)
			(layer "F.Fab")
		)
		(fp_line
			(start 0.67945 -0.3048)
			(end 0.67945 0.3048)
			(stroke
				(width 0.1)
				(type default)
			)
			(layer "F.Fab")
		)
		(fp_line
			(start 0.12065 -0.3048)
			(end 0.67945 -0.3048)
			(stroke
				(width 0.1)
				(type default)
			)
			(layer "F.Fab")
		)
		(fp_line
			(start 0.12065 -0.2794)
			(end 0.12065 -0.3048)
			(stroke
				(width 0.1)
				(type default)
			)
			(layer "F.Fab")
		)
		(fp_line
			(start -0.12065 -0.2794)
			(end 0.12065 -0.2794)
			(stroke
				(width 0.1)
				(type default)
			)
			(layer "F.Fab")
		)
		(fp_line
			(start 0.120396 0.2794)
			(end -0.12065 0.2794)
			(stroke
				(width 0.1)
				(type default)
			)
			(layer "F.Fab")
		)
		(fp_line
			(start -0.12065 0.2794)
			(end -0.12065 0.3048)
			(stroke
				(width 0.1)
				(type default)
			)
			(layer "F.Fab")
		)
		(fp_line
			(start 0.67945 0.3048)
			(end 0.120396 0.3048)
			(stroke
				(width 0.1)
				(type default)
			)
			(layer "F.Fab")
		)
		(fp_line
			(start 0.120396 0.3048)
			(end 0.120396 0.2794)
			(stroke
				(width 0.1)
				(type default)
			)
			(layer "F.Fab")
		)
		(fp_line
			(start -0.12065 0.3048)
			(end -0.67945 0.3048)
			(stroke
				(width 0.1)
				(type default)
			)
			(layer "F.Fab")
		)
		(fp_line
			(start -0.67945 0.3048)
			(end -0.67945 -0.305054)
			(stroke
				(width 0.1)
				(type default)
			)
			(layer "F.Fab")
		)
		(pad "1" smd circle
			(at -0.40005 0 90)
			(size 0 0)
			(layers "F.Cu" "F.Mask" "F.Paste")
			(net "MB_BIC_READY_BUF_N")
		)
		(pad "2" smd circle
			(at 0.40005 0 90)
			(size 0 0)
			(layers "F.Cu" "F.Mask" "F.Paste")
			(net "MB_BIC_READY_BUF_R_N")
		)
	)
)
